(kicad_pcb
	(version 20260206)
	(generator "pcbnew")
	(generator_version "10.0")
	(general
		(thickness 1.6)
		(legacy_teardrops no)
	)
	(paper "A4")
	(title_block
		(title "01162023_DA0F0TEBIF0_F0T_Expander_BD_F_brd_V02_OCP.brd")
		(comment 1 "Grand Teton / footprint 6602 of 9728 (PEX1), pads 1883-1999 of 2397")
	)
	(layers
		(0 "F.Cu" signal "TOP")
		(4 "In1.Cu" signal "GND")
		(6 "In2.Cu" signal "VCC")
		(8 "In3.Cu" signal "VCC1")
		(10 "In4.Cu" signal "GND1")
		(12 "In5.Cu" signal "IN1")
		(14 "In6.Cu" signal "GND2")
		(16 "In7.Cu" signal "IN2")
		(18 "In8.Cu" signal "GND3")
		(20 "In9.Cu" signal "IN3")
		(22 "In10.Cu" signal "GND4")
		(24 "In11.Cu" signal "IN4")
		(26 "In12.Cu" signal "GND5")
		(28 "In13.Cu" signal "IN5")
		(30 "In14.Cu" signal "GND6")
		(32 "In15.Cu" signal "IN6")
		(34 "In16.Cu" signal "GND7")
		(2 "B.Cu" signal "BOTTOM")
		(9 "F.Adhes" user "F.Adhesive")
		(11 "B.Adhes" user "B.Adhesive")
		(13 "F.Paste" user "Package Geometry/Pastemask Top")
		(15 "B.Paste" user "Package Geometry/Pastemask Bottom")
		(5 "F.SilkS" user "Ref Des/Silkscreen Top")
		(7 "B.SilkS" user "Ref Des/Silkscreen Bottom")
		(1 "F.Mask" user "Board Geometry/Soldermask Top")
		(3 "B.Mask" user "Board Geometry/Soldermask Bottom")
		(17 "Dwgs.User" user "User.Drawings")
		(19 "Cmts.User" user "User.Comments")
		(21 "Eco1.User" user "User.Eco1")
		(23 "Eco2.User" user "User.Eco2")
		(25 "Edge.Cuts" user "Board Geometry/Outline")
		(27 "Margin" user)
		(31 "F.CrtYd" user "Package Geometry/Place Bound Top")
		(29 "B.CrtYd" user "Package Geometry/Place Bound Bottom")
		(35 "F.Fab" user "Ref Des/Assembly Top")
		(33 "B.Fab" user "Ref Des/Assembly Bottom")
	)
	(footprint ""
		(layer "F.Cu")
		(at 175.749966 -295.89984)
		(property "Reference" "PEX1"
			(at -3.353562 35.593274 0)
			(unlocked yes)
			(layer "F.SilkS")
			(effects
				(font
					(size 2.032 1.524)
					(thickness 0.1524)
				)
				(justify left)
			)
		)
		(property "Value" ""
			(at 0 0 0)
			(layer "F.Fab")
			(effects
				(font
					(size 1.27 1.27)
				)
			)
		)
		(duplicate_pad_numbers_are_jumpers no)
		(pad "K25" smd circle
			(at 0 -14.249908)
			(size 0.4572 0.4572)
			(layers "F.Cu" "F.Mask" "F.Paste")
			(net "GND")
		)
		(pad "K26" smd circle
			(at 0.94996 -14.249908)
			(size 0.4572 0.4572)
			(layers "F.Cu" "F.Mask" "F.Paste")
			(net "GND")
		)
		(pad "K27" smd circle
			(at 1.89992 -14.249908)
			(size 0.4572 0.4572)
			(layers "F.Cu" "F.Mask" "F.Paste")
			(net "GND")
		)
		(pad "K28" smd circle
			(at 2.84988 -14.249908)
			(size 0.4572 0.4572)
			(layers "F.Cu" "F.Mask" "F.Paste")
			(net "GND")
		)
		(pad "K29" smd circle
			(at 3.800094 -14.249908)
			(size 0.4572 0.4572)
			(layers "F.Cu" "F.Mask" "F.Paste")
			(net "GND")
		)
		(pad "K30" smd circle
			(at 4.750054 -14.249908)
			(size 0.4572 0.4572)
			(layers "F.Cu" "F.Mask" "F.Paste")
			(net "GND")
		)
		(pad "K31" smd circle
			(at 5.700014 -14.249908)
			(size 0.4572 0.4572)
			(layers "F.Cu" "F.Mask" "F.Paste")
			(net "GND")
		)
		(pad "K32" smd circle
			(at 6.649974 -14.249908)
			(size 0.4572 0.4572)
			(layers "F.Cu" "F.Mask" "F.Paste")
			(net "GND")
		)
		(pad "K33" smd circle
			(at 7.599934 -14.249908)
			(size 0.4572 0.4572)
			(layers "F.Cu" "F.Mask" "F.Paste")
			(net "GND")
		)
		(pad "K34" smd circle
			(at 8.549894 -14.249908)
			(size 0.4572 0.4572)
			(layers "F.Cu" "F.Mask" "F.Paste")
			(net "GND")
		)
		(pad "K35" smd circle
			(at 9.500108 -14.249908)
			(size 0.4572 0.4572)
			(layers "F.Cu" "F.Mask" "F.Paste")
			(net "GND")
		)
		(pad "K36" smd circle
			(at 10.450068 -14.249908)
			(size 0.4572 0.4572)
			(layers "F.Cu" "F.Mask" "F.Paste")
			(net "GND")
		)
		(pad "K37" smd circle
			(at 11.400028 -14.249908)
			(size 0.4572 0.4572)
			(layers "F.Cu" "F.Mask" "F.Paste")
			(net "GND")
		)
		(pad "K38" smd circle
			(at 12.349988 -14.249908)
			(size 0.4572 0.4572)
			(layers "F.Cu" "F.Mask" "F.Paste")
			(net "GND")
		)
		(pad "K39" smd circle
			(at 13.299948 -14.249908)
			(size 0.4572 0.4572)
			(layers "F.Cu" "F.Mask" "F.Paste")
			(net "GND")
		)
		(pad "K40" smd circle
			(at 14.249908 -14.249908)
			(size 0.4572 0.4572)
			(layers "F.Cu" "F.Mask" "F.Paste")
			(net "GND")
		)
		(pad "K41" smd circle
			(at 15.200122 -14.249908)
			(size 0.4572 0.4572)
			(layers "F.Cu" "F.Mask" "F.Paste")
			(net "GND")
		)
		(pad "K42" smd circle
			(at 16.150082 -14.249908)
			(size 0.4572 0.4572)
			(layers "F.Cu" "F.Mask" "F.Paste")
			(net "GND")
		)
		(pad "K43" smd circle
			(at 17.100042 -14.249908)
			(size 0.4572 0.4572)
			(layers "F.Cu" "F.Mask" "F.Paste")
			(net "GND")
		)
		(pad "K44" smd circle
			(at 18.050002 -14.249908)
			(size 0.4572 0.4572)
			(layers "F.Cu" "F.Mask" "F.Paste")
			(net "GND")
		)
		(pad "K45" smd circle
			(at 18.999962 -14.249908)
			(size 0.4572 0.4572)
			(layers "F.Cu" "F.Mask" "F.Paste")
			(net "GND")
		)
		(pad "K46" smd circle
			(at 19.949922 -14.249908)
			(size 0.4572 0.4572)
			(layers "F.Cu" "F.Mask" "F.Paste")
			(net "GND")
		)
		(pad "K47" smd circle
			(at 20.899882 -14.249908)
			(size 0.4572 0.4572)
			(layers "F.Cu" "F.Mask" "F.Paste")
			(net "GND")
		)
		(pad "K48" smd circle
			(at 21.850096 -14.249908)
			(size 0.4572 0.4572)
			(layers "F.Cu" "F.Mask" "F.Paste")
			(net "P5E_PEX1_STN4_RX_DP<70>")
		)
		(pad "K49" smd circle
			(at 22.800056 -14.249908)
			(size 0.4572 0.4572)
			(layers "F.Cu" "F.Mask" "F.Paste")
			(net "P5E_PEX1_STN4_RX_DN<70>")
		)
		(pad "L1" smd circle
			(at -22.800056 -13.299948)
			(size 0.4572 0.4572)
			(layers "F.Cu" "F.Mask" "F.Paste")
			(net "GND")
		)
		(pad "L2" smd circle
			(at -21.850096 -13.299948)
			(size 0.4572 0.4572)
			(layers "F.Cu" "F.Mask" "F.Paste")
			(net "GND")
		)
		(pad "L3" smd circle
			(at -20.899882 -13.299948)
			(size 0.4572 0.4572)
			(layers "F.Cu" "F.Mask" "F.Paste")
			(net "P5E_PEX1_STN7_RX_DN<120>")
		)
		(pad "L4" smd circle
			(at -19.949922 -13.299948)
			(size 0.4572 0.4572)
			(layers "F.Cu" "F.Mask" "F.Paste")
			(net "P5E_PEX1_STN7_RX_DP<120>")
		)
		(pad "L5" smd circle
			(at -18.999962 -13.299948)
			(size 0.4572 0.4572)
			(layers "F.Cu" "F.Mask" "F.Paste")
			(net "GND")
		)
		(pad "L6" smd circle
			(at -18.050002 -13.299948)
			(size 0.4572 0.4572)
			(layers "F.Cu" "F.Mask" "F.Paste")
			(net "P5E_PEX1_STN7_TX_DN<120>")
		)
		(pad "L7" smd circle
			(at -17.100042 -13.299948)
			(size 0.4572 0.4572)
			(layers "F.Cu" "F.Mask" "F.Paste")
			(net "P5E_PEX1_STN7_TX_DP<120>")
		)
		(pad "L8" smd circle
			(at -16.150082 -13.299948)
			(size 0.4572 0.4572)
			(layers "F.Cu" "F.Mask" "F.Paste")
			(net "GND")
		)
		(pad "L9" smd circle
			(at -15.200122 -13.299948)
			(size 0.4572 0.4572)
			(layers "F.Cu" "F.Mask" "F.Paste")
			(net "GND")
		)
		(pad "L10" smd circle
			(at -14.249908 -13.299948)
			(size 0.4572 0.4572)
			(layers "F.Cu" "F.Mask" "F.Paste")
			(net "GND")
		)
		(pad "L11" smd circle
			(at -13.299948 -13.299948)
			(size 0.4572 0.4572)
			(layers "F.Cu" "F.Mask" "F.Paste")
			(net "GND")
		)
		(pad "L12" smd circle
			(at -12.349988 -13.299948)
			(size 0.4572 0.4572)
			(layers "F.Cu" "F.Mask" "F.Paste")
			(net "PEX1_DBG_MODE0")
		)
		(pad "L13" smd circle
			(at -11.400028 -13.299948)
			(size 0.4572 0.4572)
			(layers "F.Cu" "F.Mask" "F.Paste")
			(net "PEX1_DBG_MODE1")
		)
		(pad "L14" smd circle
			(at -10.450068 -13.299948)
			(size 0.4572 0.4572)
			(layers "F.Cu" "F.Mask" "F.Paste")
			(net "GND")
		)
		(pad "L15" smd circle
			(at -9.500108 -13.299948)
			(size 0.4572 0.4572)
			(layers "F.Cu" "F.Mask" "F.Paste")
			(net "PU_PEX1_ATPG_MODE_L")
		)
		(pad "L16" smd circle
			(at -8.549894 -13.299948)
			(size 0.4572 0.4572)
			(layers "F.Cu" "F.Mask" "F.Paste")
			(net "PU_PEX1_PAD_TRI_L")
		)
		(pad "L17" smd circle
			(at -7.599934 -13.299948)
			(size 0.4572 0.4572)
			(layers "F.Cu" "F.Mask" "F.Paste")
			(net "TP_PEX1_TDI")
		)
		(pad "L18" smd circle
			(at -6.649974 -13.299948)
			(size 0.4572 0.4572)
			(layers "F.Cu" "F.Mask" "F.Paste")
			(net "PEX1_DBG_SEL0")
		)
		(pad "L19" smd circle
			(at -5.700014 -13.299948)
			(size 0.4572 0.4572)
			(layers "F.Cu" "F.Mask" "F.Paste")
			(net "TP_PEX1_TDO")
		)
		(pad "L20" smd circle
			(at -4.750054 -13.299948)
			(size 0.4572 0.4572)
			(layers "F.Cu" "F.Mask" "F.Paste")
			(net "PU_PEX1_TR_TCK")
		)
		(pad "L21" smd circle
			(at -3.800094 -13.299948)
			(size 0.4572 0.4572)
			(layers "F.Cu" "F.Mask" "F.Paste")
			(net "GND")
		)
		(pad "L22" smd circle
			(at -2.84988 -13.299948)
			(size 0.4572 0.4572)
			(layers "F.Cu" "F.Mask" "F.Paste")
			(net "Net_5289")
		)
		(pad "L23" smd circle
			(at -1.89992 -13.299948)
			(size 0.4572 0.4572)
			(layers "F.Cu" "F.Mask" "F.Paste")
			(net "Net_5293")
		)
		(pad "L24" smd circle
			(at -0.94996 -13.299948)
			(size 0.4572 0.4572)
			(layers "F.Cu" "F.Mask" "F.Paste")
			(net "Net_5288")
		)
		(pad "L25" smd circle
			(at 0 -13.299948)
			(size 0.4572 0.4572)
			(layers "F.Cu" "F.Mask" "F.Paste")
			(net "PEX1_SPARE5")
		)
		(pad "L26" smd circle
			(at 0.94996 -13.299948)
			(size 0.4572 0.4572)
			(layers "F.Cu" "F.Mask" "F.Paste")
			(net "PU_PEX1_SIO_BLINK")
		)
		(pad "L27" smd circle
			(at 1.89992 -13.299948)
			(size 0.4572 0.4572)
			(layers "F.Cu" "F.Mask" "F.Paste")
			(net "PEX1_SPARE2")
		)
		(pad "L28" smd circle
			(at 2.84988 -13.299948)
			(size 0.4572 0.4572)
			(layers "F.Cu" "F.Mask" "F.Paste")
			(net "PEX1_SPARE6")
		)
		(pad "L29" smd circle
			(at 3.800094 -13.299948)
			(size 0.4572 0.4572)
			(layers "F.Cu" "F.Mask" "F.Paste")
			(net "Net_5278")
		)
		(pad "L30" smd circle
			(at 4.750054 -13.299948)
			(size 0.4572 0.4572)
			(layers "F.Cu" "F.Mask" "F.Paste")
			(net "PEX1_SPARE1")
		)
		(pad "L31" smd circle
			(at 5.700014 -13.299948)
			(size 0.4572 0.4572)
			(layers "F.Cu" "F.Mask" "F.Paste")
			(net "Net_5282")
		)
		(pad "L32" smd circle
			(at 6.649974 -13.299948)
			(size 0.4572 0.4572)
			(layers "F.Cu" "F.Mask" "F.Paste")
			(net "PEX1_SPARE3")
		)
		(pad "L33" smd circle
			(at 7.599934 -13.299948)
			(size 0.4572 0.4572)
			(layers "F.Cu" "F.Mask" "F.Paste")
			(net "Net_5274")
		)
		(pad "L34" smd circle
			(at 8.549894 -13.299948)
			(size 0.4572 0.4572)
			(layers "F.Cu" "F.Mask" "F.Paste")
			(net "SMB_PEX1_SLAVE1_SCL")
		)
		(pad "L35" smd circle
			(at 9.500108 -13.299948)
			(size 0.4572 0.4572)
			(layers "F.Cu" "F.Mask" "F.Paste")
			(net "Net_5271")
		)
		(pad "L36" smd circle
			(at 10.450068 -13.299948)
			(size 0.4572 0.4572)
			(layers "F.Cu" "F.Mask" "F.Paste")
			(net "Net_5301")
		)
		(pad "L37" smd circle
			(at 11.400028 -13.299948)
			(size 0.4572 0.4572)
			(layers "F.Cu" "F.Mask" "F.Paste")
			(net "PEX1_EXT_GPIO_LATCH_N")
		)
		(pad "L38" smd circle
			(at 12.349988 -13.299948)
			(size 0.4572 0.4572)
			(layers "F.Cu" "F.Mask" "F.Paste")
			(net "Net_5298")
		)
		(pad "L39" smd circle
			(at 13.299948 -13.299948)
			(size 0.4572 0.4572)
			(layers "F.Cu" "F.Mask" "F.Paste")
			(net "SMB_PEX1_SLAVE_SDA")
		)
		(pad "L40" smd circle
			(at 14.249908 -13.299948)
			(size 0.4572 0.4572)
			(layers "F.Cu" "F.Mask" "F.Paste")
			(net "GND")
		)
		(pad "L41" smd circle
			(at 15.200122 -13.299948)
			(size 0.4572 0.4572)
			(layers "F.Cu" "F.Mask" "F.Paste")
			(net "GND")
		)
		(pad "L42" smd circle
			(at 16.150082 -13.299948)
			(size 0.4572 0.4572)
			(layers "F.Cu" "F.Mask" "F.Paste")
			(net "GND")
		)
		(pad "L43" smd circle
			(at 17.100042 -13.299948)
			(size 0.4572 0.4572)
			(layers "F.Cu" "F.Mask" "F.Paste")
			(net "P5E_PEX1_STN4_TX_DP<69>")
		)
		(pad "L44" smd circle
			(at 18.050002 -13.299948)
			(size 0.4572 0.4572)
			(layers "F.Cu" "F.Mask" "F.Paste")
			(net "P5E_PEX1_STN4_TX_DN<69>")
		)
		(pad "L45" smd circle
			(at 18.999962 -13.299948)
			(size 0.4572 0.4572)
			(layers "F.Cu" "F.Mask" "F.Paste")
			(net "GND")
		)
		(pad "L46" smd circle
			(at 19.949922 -13.299948)
			(size 0.4572 0.4572)
			(layers "F.Cu" "F.Mask" "F.Paste")
			(net "P5E_PEX1_STN4_RX_DP<69>")
		)
		(pad "L47" smd circle
			(at 20.899882 -13.299948)
			(size 0.4572 0.4572)
			(layers "F.Cu" "F.Mask" "F.Paste")
			(net "P5E_PEX1_STN4_RX_DN<69>")
		)
		(pad "L48" smd circle
			(at 21.850096 -13.299948)
			(size 0.4572 0.4572)
			(layers "F.Cu" "F.Mask" "F.Paste")
			(net "GND")
		)
		(pad "L49" smd circle
			(at 22.800056 -13.299948)
			(size 0.4572 0.4572)
			(layers "F.Cu" "F.Mask" "F.Paste")
			(net "GND")
		)
		(pad "M1" smd circle
			(at -22.800056 -12.349988)
			(size 0.4572 0.4572)
			(layers "F.Cu" "F.Mask" "F.Paste")
			(net "P5E_PEX1_STN7_RX_DN<119>")
		)
		(pad "M2" smd circle
			(at -21.850096 -12.349988)
			(size 0.4572 0.4572)
			(layers "F.Cu" "F.Mask" "F.Paste")
			(net "P5E_PEX1_STN7_RX_DP<119>")
		)
		(pad "M3" smd circle
			(at -20.899882 -12.349988)
			(size 0.4572 0.4572)
			(layers "F.Cu" "F.Mask" "F.Paste")
			(net "GND")
		)
		(pad "M4" smd circle
			(at -19.949922 -12.349988)
			(size 0.4572 0.4572)
			(layers "F.Cu" "F.Mask" "F.Paste")
			(net "GND")
		)
		(pad "M5" smd circle
			(at -18.999962 -12.349988)
			(size 0.4572 0.4572)
			(layers "F.Cu" "F.Mask" "F.Paste")
			(net "GND")
		)
		(pad "M6" smd circle
			(at -18.050002 -12.349988)
			(size 0.4572 0.4572)
			(layers "F.Cu" "F.Mask" "F.Paste")
			(net "GND")
		)
		(pad "M7" smd circle
			(at -17.100042 -12.349988)
			(size 0.4572 0.4572)
			(layers "F.Cu" "F.Mask" "F.Paste")
			(net "GND")
		)
		(pad "M8" smd circle
			(at -16.150082 -12.349988)
			(size 0.4572 0.4572)
			(layers "F.Cu" "F.Mask" "F.Paste")
			(net "P5E_PEX1_STN7_TX_DN<119>")
		)
		(pad "M9" smd circle
			(at -15.200122 -12.349988)
			(size 0.4572 0.4572)
			(layers "F.Cu" "F.Mask" "F.Paste")
			(net "P5E_PEX1_STN7_TX_DP<119>")
		)
		(pad "M10" smd circle
			(at -14.249908 -12.349988)
			(size 0.4572 0.4572)
			(layers "F.Cu" "F.Mask" "F.Paste")
			(net "GND")
		)
		(pad "M11" smd circle
			(at -13.299948 -12.349988)
			(size 0.4572 0.4572)
			(layers "F.Cu" "F.Mask" "F.Paste")
			(net "GND")
		)
		(pad "M12" smd circle
			(at -12.349988 -12.349988)
			(size 0.4572 0.4572)
			(layers "F.Cu" "F.Mask" "F.Paste")
			(net "GND")
		)
		(pad "M13" smd circle
			(at -11.400028 -12.349988)
			(size 0.4572 0.4572)
			(layers "F.Cu" "F.Mask" "F.Paste")
			(net "IRQ_PEX1_CLKREQ_INT_N")
		)
		(pad "M14" smd circle
			(at -10.450068 -12.349988)
			(size 0.4572 0.4572)
			(layers "F.Cu" "F.Mask" "F.Paste")
			(net "GND")
		)
		(pad "M15" smd circle
			(at -9.500108 -12.349988)
			(size 0.4572 0.4572)
			(layers "F.Cu" "F.Mask" "F.Paste")
			(net "TP_PEX1_TCK")
		)
		(pad "M16" smd circle
			(at -8.549894 -12.349988)
			(size 0.4572 0.4572)
			(layers "F.Cu" "F.Mask" "F.Paste")
			(net "PEX1_DFT_IDDT")
		)
		(pad "M17" smd circle
			(at -7.599934 -12.349988)
			(size 0.4572 0.4572)
			(layers "F.Cu" "F.Mask" "F.Paste")
			(net "RST_PEX1_SYS_N")
		)
		(pad "M18" smd circle
			(at -6.649974 -12.349988)
			(size 0.4572 0.4572)
			(layers "F.Cu" "F.Mask" "F.Paste")
			(net "TP_PEX1_TRST_L")
		)
		(pad "M19" smd circle
			(at -5.700014 -12.349988)
			(size 0.4572 0.4572)
			(layers "F.Cu" "F.Mask" "F.Paste")
			(net "PEX1_DBG_SEL1")
		)
		(pad "M20" smd circle
			(at -4.750054 -12.349988)
			(size 0.4572 0.4572)
			(layers "F.Cu" "F.Mask" "F.Paste")
			(net "TP_PEX1_TMS")
		)
		(pad "M21" smd circle
			(at -3.800094 -12.349988)
			(size 0.4572 0.4572)
			(layers "F.Cu" "F.Mask" "F.Paste")
			(net "GND")
		)
		(pad "M22" smd circle
			(at -2.84988 -12.349988)
			(size 0.4572 0.4572)
			(layers "F.Cu" "F.Mask" "F.Paste")
			(net "Net_5291")
		)
		(pad "M23" smd circle
			(at -1.89992 -12.349988)
			(size 0.4572 0.4572)
			(layers "F.Cu" "F.Mask" "F.Paste")
			(net "Net_5292")
		)
		(pad "M24" smd circle
			(at -0.94996 -12.349988)
			(size 0.4572 0.4572)
			(layers "F.Cu" "F.Mask" "F.Paste")
			(net "Net_5294")
		)
		(pad "M25" smd circle
			(at 0 -12.349988)
			(size 0.4572 0.4572)
			(layers "F.Cu" "F.Mask" "F.Paste")
			(net "PEX1_SPARE4")
		)
		(pad "M26" smd circle
			(at 0.94996 -12.349988)
			(size 0.4572 0.4572)
			(layers "F.Cu" "F.Mask" "F.Paste")
			(net "PEX1_SPARE0")
		)
		(pad "M27" smd circle
			(at 1.89992 -12.349988)
			(size 0.4572 0.4572)
			(layers "F.Cu" "F.Mask" "F.Paste")
			(net "PEX1_SPARE7")
		)
		(pad "M28" smd circle
			(at 2.84988 -12.349988)
			(size 0.4572 0.4572)
			(layers "F.Cu" "F.Mask" "F.Paste")
			(net "I2C0_PEX1_SHPC_SDA")
		)
		(pad "M29" smd circle
			(at 3.800094 -12.349988)
			(size 0.4572 0.4572)
			(layers "F.Cu" "F.Mask" "F.Paste")
			(net "I2C0_PEX1_SHPC_SCL")
		)
		(pad "M30" smd circle
			(at 4.750054 -12.349988)
			(size 0.4572 0.4572)
			(layers "F.Cu" "F.Mask" "F.Paste")
			(net "Net_5272")
		)
		(pad "M31" smd circle
			(at 5.700014 -12.349988)
			(size 0.4572 0.4572)
			(layers "F.Cu" "F.Mask" "F.Paste")
			(net "Net_5273")
		)
		(pad "M32" smd circle
			(at 6.649974 -12.349988)
			(size 0.4572 0.4572)
			(layers "F.Cu" "F.Mask" "F.Paste")
			(net "Net_5283")
		)
		(pad "M33" smd circle
			(at 7.599934 -12.349988)
			(size 0.4572 0.4572)
			(layers "F.Cu" "F.Mask" "F.Paste")
			(net "Net_5277")
		)
		(pad "M34" smd circle
			(at 8.549894 -12.349988)
			(size 0.4572 0.4572)
			(layers "F.Cu" "F.Mask" "F.Paste")
			(net "Net_5281")
		)
		(pad "M35" smd circle
			(at 9.500108 -12.349988)
			(size 0.4572 0.4572)
			(layers "F.Cu" "F.Mask" "F.Paste")
			(net "I2C0_PEX1_SCL")
		)
		(pad "M36" smd circle
			(at 10.450068 -12.349988)
			(size 0.4572 0.4572)
			(layers "F.Cu" "F.Mask" "F.Paste")
			(net "Net_5300")
		)
		(pad "M37" smd circle
			(at 11.400028 -12.349988)
			(size 0.4572 0.4572)
			(layers "F.Cu" "F.Mask" "F.Paste")
			(net "Net_5299")
		)
		(pad "M38" smd circle
			(at 12.349988 -12.349988)
			(size 0.4572 0.4572)
			(layers "F.Cu" "F.Mask" "F.Paste")
			(net "SMB_PEX1_SLAVE1_SDA")
		)
		(pad "M39" smd circle
			(at 13.299948 -12.349988)
			(size 0.4572 0.4572)
			(layers "F.Cu" "F.Mask" "F.Paste")
			(net "I2C0_PEX1_SDA")
		)
		(pad "M40" smd circle
			(at 14.249908 -12.349988)
			(size 0.4572 0.4572)
			(layers "F.Cu" "F.Mask" "F.Paste")
			(net "GND")
		)
		(pad "M41" smd circle
			(at 15.200122 -12.349988)
			(size 0.4572 0.4572)
			(layers "F.Cu" "F.Mask" "F.Paste")
			(net "P5E_PEX1_STN4_TX_DP<68>")
		)
		(pad "M42" smd circle
			(at 16.150082 -12.349988)
			(size 0.4572 0.4572)
			(layers "F.Cu" "F.Mask" "F.Paste")
			(net "P5E_PEX1_STN4_TX_DN<68>")
		)
		(pad "M43" smd circle
			(at 17.100042 -12.349988)
			(size 0.4572 0.4572)
			(layers "F.Cu" "F.Mask" "F.Paste")
			(net "GND")
		)
	)
)
